(kicad_pcb
	(version 20241229)
	(generator "pcbnew")
	(generator_version "9.0")
	(general
		(thickness 1.711)
		(legacy_teardrops no)
	)
	(paper "A4")
	(title_block
		(title "Antmicro Baseboard for Jetson AGX Thor")
		(date "2026-02-18")
		(rev "1.1.0")
		(company "Antmicro Ltd")
		(comment 1 "www.antmicro.com")
		(comment 9 "footprints 837-841 of 1170")
	)
	(layers
		(0 "F.Cu" signal)
		(4 "In1.Cu" signal)
		(6 "In2.Cu" signal)
		(8 "In3.Cu" signal)
		(10 "In4.Cu" jumper)
		(12 "In5.Cu" signal)
		(14 "In6.Cu" signal)
		(16 "In7.Cu" signal)
		(18 "In8.Cu" signal)
		(2 "B.Cu" signal)
		(9 "F.Adhes" user "F.Adhesive")
		(11 "B.Adhes" user "B.Adhesive")
		(13 "F.Paste" user)
		(15 "B.Paste" user)
		(5 "F.SilkS" user "F.Silkscreen")
		(7 "B.SilkS" user "B.Silkscreen")
		(1 "F.Mask" user)
		(3 "B.Mask" user)
		(17 "Dwgs.User" user "User.Drawings")
		(19 "Cmts.User" user "User.Comments")
		(21 "Eco1.User" user "User.Eco1")
		(23 "Eco2.User" user "User.Eco2")
		(25 "Edge.Cuts" user)
		(27 "Margin" user)
		(31 "F.CrtYd" user "F.Courtyard")
		(29 "B.CrtYd" user "B.Courtyard")
		(35 "F.Fab" user)
		(33 "B.Fab" user)
	)
	(footprint "antmicro-footprints:R_0603_1608Metric"
		(layer "B.Cu")
		(at 124.6 95.5)
		(descr "Resistor SMD 0603")
		(tags "resistor SMD 0603")
		(property "Reference" "R213"
			(at 1.2 -0.3 0)
			(layer "B.SilkS")
			(effects
				(font
					(size 0.7 0.7)
					(thickness 0.15)
				)
				(justify right top mirror)
			)
		)
		(property "Value" "R_0R_22.4A_0603"
			(at 0 -1.6 0)
			(layer "B.Fab")
			(effects
				(font
					(size 0.7 0.7)
					(thickness 0.15)
				)
				(justify right top mirror)
			)
		)
		(property "Datasheet" "https://fscdn.rohm.com/en/products/databook/datasheet/passive/resistor/chip_resistor/pmr-jpw-e.pdf"
			(at 0 0 0)
			(layer "B.Fab")
			(hide yes)
			(effects
				(font
					(size 1.27 1.27)
					(thickness 0.15)
				)
				(justify mirror)
			)
		)
		(property "Description" "SMD Chip Resistor"
			(at 0 0 0)
			(layer "B.Fab")
			(hide yes)
			(effects
				(font
					(size 1.27 1.27)
					(thickness 0.15)
				)
				(justify mirror)
			)
		)
		(property "Manufacturer" "ROHM Semiconductor"
			(at 0 0 180)
			(unlocked yes)
			(layer "B.Fab")
			(hide yes)
			(effects
				(font
					(size 1 1)
					(thickness 0.15)
				)
				(justify mirror)
			)
		)
		(property "MPN" "PMR03EZPJ000"
			(at 0 0 180)
			(unlocked yes)
			(layer "B.Fab")
			(hide yes)
			(effects
				(font
					(size 1 1)
					(thickness 0.15)
				)
				(justify mirror)
			)
		)
		(property "Val" "0R"
			(at 0 0 180)
			(unlocked yes)
			(layer "B.Fab")
			(hide yes)
			(effects
				(font
					(size 1 1)
					(thickness 0.15)
				)
				(justify mirror)
			)
		)
		(property "Author" "Antmicro"
			(at 0 0 180)
			(unlocked yes)
			(layer "B.Fab")
			(hide yes)
			(effects
				(font
					(size 1 1)
					(thickness 0.15)
				)
				(justify mirror)
			)
		)
		(property "License" "Apache-2.0"
			(at 0 0 180)
			(unlocked yes)
			(layer "B.Fab")
			(hide yes)
			(effects
				(font
					(size 1 1)
					(thickness 0.15)
				)
				(justify mirror)
			)
		)
		(property "Max. Curr." "22.4A"
			(at 0 0 180)
			(unlocked yes)
			(layer "B.Fab")
			(hide yes)
			(effects
				(font
					(size 1 1)
					(thickness 0.15)
				)
				(justify mirror)
			)
		)
		(property "Tolerance" "template_tolerance"
			(at 0 0 180)
			(unlocked yes)
			(layer "B.Fab")
			(hide yes)
			(effects
				(font
					(size 1 1)
					(thickness 0.15)
				)
				(justify mirror)
			)
		)
		(sheetname "/M.2/")
		(sheetfile "m2.kicad_sch")
		(attr smd)
		(fp_line
			(start -0.15 -0.4)
			(end 0.15 -0.4)
			(stroke
				(width 0.15)
				(type solid)
			)
			(layer "B.SilkS")
		)
		(fp_line
			(start -0.15 0.4)
			(end 0.15 0.4)
			(stroke
				(width 0.15)
				(type solid)
			)
			(layer "B.SilkS")
		)
		(fp_poly
			(pts
				(xy -1.25 0.65) (xy 1.25 0.65) (xy 1.25 -0.65) (xy -1.25 -0.65)
			)
			(stroke
				(width 0.05)
				(type solid)
			)
			(fill no)
			(layer "B.CrtYd")
		)
		(fp_poly
			(pts
				(xy -0.8 0.4) (xy 0.8 0.4) (xy 0.8 -0.4) (xy -0.8 -0.4)
			)
			(stroke
				(width 0.15)
				(type solid)
			)
			(fill no)
			(layer "B.Fab")
		)
		(fp_text user "${REFERENCE}"
			(at -1.25 -3.898 0)
			(layer "B.Fab")
			(effects
				(font
					(size 0.7 0.7)
					(thickness 0.15)
				)
				(justify right top mirror)
			)
		)
		(fp_text user "Author: Antmicro"
			(at -1.25 -4.9 0)
			(layer "B.Fab")
			(effects
				(font
					(size 0.7 0.7)
					(thickness 0.15)
				)
				(justify right top mirror)
			)
		)
		(fp_text user "License: Apache-2.0"
			(at -1.249999 -5.9 0)
			(layer "B.Fab")
			(effects
				(font
					(size 0.7 0.7)
					(thickness 0.15)
				)
				(justify right top mirror)
			)
		)
		(pad "1" smd roundrect
			(at -0.7 0)
			(size 0.8 1)
			(layers "B.Cu" "B.Mask" "B.Paste")
			(roundrect_rratio 0.2)
			(net 14 "/M.2/3V3_M2")
			(pintype "passive")
		)
		(pad "2" smd roundrect
			(at 0.7 0)
			(size 0.8 1)
			(layers "B.Cu" "B.Mask" "B.Paste")
			(roundrect_rratio 0.2)
			(net 2 "+3V3")
			(pintype "passive")
		)
	)
	(footprint "antmicro-footprints:TP_SMD_0.75mm"
		(layer "B.Cu")
		(at 91.17 62.68 180)
		(property "Reference" "TP122"
			(at -0.45 3.82 90)
			(layer "B.SilkS")
			(effects
				(font
					(size 0.7 0.7)
					(thickness 0.15)
				)
				(justify left bottom mirror)
			)
		)
		(property "Value" "TP_0.75mm_SMD"
			(at 0 -1.2 0)
			(layer "B.Fab")
			(effects
				(font
					(size 0.7 0.7)
					(thickness 0.15)
				)
				(justify left bottom mirror)
			)
		)
		(property "Description" "SMT test point"
			(at 0 0 0)
			(layer "B.Fab")
			(hide yes)
			(effects
				(font
					(size 1.27 1.27)
					(thickness 0.15)
				)
				(justify mirror)
			)
		)
		(property "MPN" ""
			(at 0 0 0)
			(unlocked yes)
			(layer "B.Fab")
			(hide yes)
			(effects
				(font
					(size 1 1)
					(thickness 0.15)
				)
				(justify mirror)
			)
		)
		(property "Manufacturer" ""
			(at 0 0 0)
			(unlocked yes)
			(layer "B.Fab")
			(hide yes)
			(effects
				(font
					(size 1 1)
					(thickness 0.15)
				)
				(justify mirror)
			)
		)
		(property "Author" "Antmicro"
			(at 0 0 0)
			(unlocked yes)
			(layer "B.Fab")
			(hide yes)
			(effects
				(font
					(size 1 1)
					(thickness 0.15)
				)
				(justify mirror)
			)
		)
		(property "License" "Apache-2.0"
			(at 0 0 0)
			(unlocked yes)
			(layer "B.Fab")
			(hide yes)
			(effects
				(font
					(size 1 1)
					(thickness 0.15)
				)
				(justify mirror)
			)
		)
		(sheetname "/SoM_Power/")
		(sheetfile "som_power.kicad_sch")
		(attr exclude_from_pos_files exclude_from_bom)
		(fp_circle
			(center 0 0)
			(end 0.475 0)
			(stroke
				(width 0.05)
				(type default)
			)
			(fill no)
			(layer "B.CrtYd")
		)
		(fp_text user "${REFERENCE}"
			(at -0.4 -2.7 0)
			(layer "B.Fab")
			(effects
				(font
					(size 0.7 0.7)
					(thickness 0.15)
				)
				(justify left bottom mirror)
			)
		)
		(fp_text user "License: Apache-2.0"
			(at -0.4 -5.101 0)
			(layer "B.Fab")
			(effects
				(font
					(size 0.7 0.7)
					(thickness 0.15)
				)
				(justify left bottom mirror)
			)
		)
		(fp_text user "Author: Antmicro"
			(at -0.4 -3.901 0)
			(layer "B.Fab")
			(effects
				(font
					(size 0.7 0.7)
					(thickness 0.15)
				)
				(justify left bottom mirror)
			)
		)
		(pad "1" smd circle
			(at 0 0 180)
			(size 0.75 0.75)
			(layers "B.Cu" "B.Mask")
			(net 1032 "/SoM_Power/~{FORCE_SHDN}")
			(pinfunction "1")
			(pintype "passive")
		)
	)
	(footprint "antmicro-footprints:TP_SMD_0.75mm"
		(layer "B.Cu")
		(at 197 123 90)
		(property "Reference" "TP6"
			(at 0.6 -2.4 0)
			(layer "B.SilkS")
			(effects
				(font
					(size 0.7 0.7)
					(thickness 0.15)
				)
				(justify right top mirror)
			)
		)
		(property "Value" "TP_0.75mm_SMD"
			(at 0 -1.2 90)
			(layer "B.Fab")
			(effects
				(font
					(size 0.7 0.7)
					(thickness 0.15)
				)
				(justify right top mirror)
			)
		)
		(property "Description" "SMT test point"
			(at 0 0 90)
			(layer "B.Fab")
			(hide yes)
			(effects
				(font
					(size 1.27 1.27)
					(thickness 0.15)
				)
				(justify mirror)
			)
		)
		(property "MPN" ""
			(at 0 0 270)
			(unlocked yes)
			(layer "B.Fab")
			(hide yes)
			(effects
				(font
					(size 1 1)
					(thickness 0.15)
				)
				(justify mirror)
			)
		)
		(property "Manufacturer" ""
			(at 0 0 270)
			(unlocked yes)
			(layer "B.Fab")
			(hide yes)
			(effects
				(font
					(size 1 1)
					(thickness 0.15)
				)
				(justify mirror)
			)
		)
		(property "Author" "Antmicro"
			(at 0 0 270)
			(unlocked yes)
			(layer "B.Fab")
			(hide yes)
			(effects
				(font
					(size 1 1)
					(thickness 0.15)
				)
				(justify mirror)
			)
		)
		(property "License" "Apache-2.0"
			(at 0 0 270)
			(unlocked yes)
			(layer "B.Fab")
			(hide yes)
			(effects
				(font
					(size 1 1)
					(thickness 0.15)
				)
				(justify mirror)
			)
		)
		(sheetname "/USB Hub/")
		(sheetfile "usb_hub.kicad_sch")
		(attr exclude_from_pos_files exclude_from_bom)
		(fp_circle
			(center 0 0)
			(end 0.475 0)
			(stroke
				(width 0.05)
				(type default)
			)
			(fill no)
			(layer "B.CrtYd")
		)
		(fp_text user "Author: Antmicro"
			(at -0.4 -3.901 90)
			(layer "B.Fab")
			(effects
				(font
					(size 0.7 0.7)
					(thickness 0.15)
				)
				(justify right top mirror)
			)
		)
		(fp_text user "${REFERENCE}"
			(at -0.4 -2.7 90)
			(layer "B.Fab")
			(effects
				(font
					(size 0.7 0.7)
					(thickness 0.15)
				)
				(justify right top mirror)
			)
		)
		(fp_text user "License: Apache-2.0"
			(at -0.4 -5.101 90)
			(layer "B.Fab")
			(effects
				(font
					(size 0.7 0.7)
					(thickness 0.15)
				)
				(justify right top mirror)
			)
		)
		(pad "1" smd circle
			(at 0 0 90)
			(size 0.75 0.75)
			(layers "B.Cu" "B.Mask")
			(net 910 "/USB Hub/PRT_CTL3")
			(pinfunction "1")
			(pintype "passive")
		)
	)
	(footprint "antmicro-footprints:R_0402_1005Metric"
		(layer "B.Cu")
		(at 63.1 70.4 90)
		(descr "Resistor SMD 0402")
		(tags "resistor SMD 0402")
		(property "Reference" "R184"
			(at -2.2 3.7 90)
			(layer "B.SilkS")
			(effects
				(font
					(size 0.7 0.7)
					(thickness 0.15)
				)
				(justify right top mirror)
			)
		)
		(property "Value" "R_0R_0402"
			(at -1.011843 -1.772047 90)
			(layer "B.Fab")
			(effects
				(font
					(size 0.7 0.7)
					(thickness 0.15)
				)
				(justify right top mirror)
			)
		)
		(property "Datasheet" "https://industrial.panasonic.com/cdbs/www-data/pdf/RDA0000/AOA0000C301.pdf"
			(at 0 0 90)
			(layer "B.Fab")
			(hide yes)
			(effects
				(font
					(size 1.27 1.27)
					(thickness 0.15)
				)
				(justify mirror)
			)
		)
		(property "Description" "SMD Chip Resistor, Jumper, 0 ohm, 100 mW, 0402 [1005 Metric], Thick Film, General Purpose"
			(at 0 0 90)
			(layer "B.Fab")
			(hide yes)
			(effects
				(font
					(size 1.27 1.27)
					(thickness 0.15)
				)
				(justify mirror)
			)
		)
		(property "MPN" "ERJ2GE0R00X"
			(at 0 0 270)
			(unlocked yes)
			(layer "B.Fab")
			(hide yes)
			(effects
				(font
					(size 1 1)
					(thickness 0.15)
				)
				(justify mirror)
			)
		)
		(property "Manufacturer" "Panasonic"
			(at 0 0 270)
			(unlocked yes)
			(layer "B.Fab")
			(hide yes)
			(effects
				(font
					(size 1 1)
					(thickness 0.15)
				)
				(justify mirror)
			)
		)
		(property "License" "Apache-2.0"
			(at 0 0 270)
			(unlocked yes)
			(layer "B.Fab")
			(hide yes)
			(effects
				(font
					(size 1 1)
					(thickness 0.15)
				)
				(justify mirror)
			)
		)
		(property "Author" "Antmicro"
			(at 0 0 270)
			(unlocked yes)
			(layer "B.Fab")
			(hide yes)
			(effects
				(font
					(size 1 1)
					(thickness 0.15)
				)
				(justify mirror)
			)
		)
		(property "Val" "0R"
			(at 0 0 270)
			(unlocked yes)
			(layer "B.Fab")
			(hide yes)
			(effects
				(font
					(size 1 1)
					(thickness 0.15)
				)
				(justify mirror)
			)
		)
		(property "Tolerance" "~"
			(at 0 0 270)
			(unlocked yes)
			(layer "B.Fab")
			(hide yes)
			(effects
				(font
					(size 1 1)
					(thickness 0.15)
				)
				(justify mirror)
			)
		)
		(property "Current" "1A"
			(at 0 0 270)
			(unlocked yes)
			(layer "B.Fab")
			(hide yes)
			(effects
				(font
					(size 1 1)
					(thickness 0.15)
				)
				(justify mirror)
			)
		)
		(sheetname "/CSI/")
		(sheetfile "csi.kicad_sch")
		(attr smd)
		(fp_rect
			(start -0.925 0.47)
			(end 0.925 -0.47)
			(stroke
				(width 0.05)
				(type default)
			)
			(fill no)
			(layer "B.CrtYd")
		)
		(fp_rect
			(start -0.5 0.25)
			(end 0.5 -0.25)
			(stroke
				(width 0.15)
				(type solid)
			)
			(fill no)
			(layer "B.Fab")
		)
		(fp_text user "Author: Antmicro"
			(at -0.95 -4.169 90)
			(layer "B.Fab")
			(effects
				(font
					(size 0.7 0.7)
					(thickness 0.15)
				)
				(justify right top mirror)
			)
		)
		(fp_text user "${REFERENCE}"
			(at -0.95 -3.168 90)
			(layer "B.Fab")
			(effects
				(font
					(size 0.7 0.7)
					(thickness 0.15)
				)
				(justify right top mirror)
			)
		)
		(fp_text user "License: Apache-2.0"
			(at -0.95 -5.169 90)
			(layer "B.Fab")
			(effects
				(font
					(size 0.7 0.7)
					(thickness 0.15)
				)
				(justify right top mirror)
			)
		)
		(pad "1" smd roundrect
			(at -0.48 0 90)
			(size 0.59 0.64)
			(layers "B.Cu" "B.Mask" "B.Paste")
			(roundrect_rratio 0.25)
			(net 1377 "Net-(J11-Pad40)")
			(pintype "passive")
		)
		(pad "2" smd roundrect
			(at 0.48 0 90)
			(size 0.59 0.64)
			(layers "B.Cu" "B.Mask" "B.Paste")
			(roundrect_rratio 0.25)
			(net 985 "/CSI/SCL_CAM0")
			(pintype "passive")
		)
	)
	(footprint "antmicro-footprints:R_0402_1005Metric"
		(layer "B.Cu")
		(at 105.35 66.01 180)
		(descr "Resistor SMD 0402")
		(tags "resistor SMD 0402")
		(property "Reference" "R5"
			(at -0.78 -1.45 0)
			(layer "B.SilkS")
			(effects
				(font
					(size 0.7 0.7)
					(thickness 0.15)
				)
				(justify left bottom mirror)
			)
		)
		(property "Value" "R_49R9_0402"
			(at -1.011843 -1.772047 0)
			(layer "B.Fab")
			(effects
				(font
					(size 0.7 0.7)
					(thickness 0.15)
				)
				(justify left bottom mirror)
			)
		)
		(property "Datasheet" "https://www.bourns.com/docs/product-datasheets/cr.pdf"
			(at 0 0 0)
			(layer "B.Fab")
			(hide yes)
			(effects
				(font
					(size 1.27 1.27)
					(thickness 0.15)
				)
				(justify mirror)
			)
		)
		(property "Description" "SMD Chip Resistor, 49.9 ohm, ± 1%, 62.5 mW, 0402 [1005 Metric], Thick Film, General Purpose"
			(at 0 0 0)
			(layer "B.Fab")
			(hide yes)
			(effects
				(font
					(size 1.27 1.27)
					(thickness 0.15)
				)
				(justify mirror)
			)
		)
		(property "MPN" "CR0402-FX-49R9GLF"
			(at 0 0 0)
			(unlocked yes)
			(layer "B.Fab")
			(hide yes)
			(effects
				(font
					(size 1 1)
					(thickness 0.15)
				)
				(justify mirror)
			)
		)
		(property "Manufacturer" "Bourns"
			(at 0 0 0)
			(unlocked yes)
			(layer "B.Fab")
			(hide yes)
			(effects
				(font
					(size 1 1)
					(thickness 0.15)
				)
				(justify mirror)
			)
		)
		(property "License" "Apache-2.0"
			(at 0 0 0)
			(unlocked yes)
			(layer "B.Fab")
			(hide yes)
			(effects
				(font
					(size 1 1)
					(thickness 0.15)
				)
				(justify mirror)
			)
		)
		(property "Author" "Antmicro"
			(at 0 0 0)
			(unlocked yes)
			(layer "B.Fab")
			(hide yes)
			(effects
				(font
					(size 1 1)
					(thickness 0.15)
				)
				(justify mirror)
			)
		)
		(property "Val" "49R9"
			(at 0 0 0)
			(unlocked yes)
			(layer "B.Fab")
			(hide yes)
			(effects
				(font
					(size 1 1)
					(thickness 0.15)
				)
				(justify mirror)
			)
		)
		(property "Tolerance" "1%"
			(at 0 0 0)
			(unlocked yes)
			(layer "B.Fab")
			(hide yes)
			(effects
				(font
					(size 1 1)
					(thickness 0.15)
				)
				(justify mirror)
			)
		)
		(sheetname "/SoM_IO2/")
		(sheetfile "som_io2.kicad_sch")
		(attr smd)
		(fp_rect
			(start -0.925 0.47)
			(end 0.925 -0.47)
			(stroke
				(width 0.05)
				(type default)
			)
			(fill no)
			(layer "B.CrtYd")
		)
		(fp_rect
			(start -0.5 0.25)
			(end 0.5 -0.25)
			(stroke
				(width 0.15)
				(type solid)
			)
			(fill no)
			(layer "B.Fab")
		)
		(fp_text user "License: Apache-2.0"
			(at -0.95 -5.169 0)
			(layer "B.Fab")
			(effects
				(font
					(size 0.7 0.7)
					(thickness 0.15)
				)
				(justify left bottom mirror)
			)
		)
		(fp_text user "Author: Antmicro"
			(at -0.95 -4.169 0)
			(layer "B.Fab")
			(effects
				(font
					(size 0.7 0.7)
					(thickness 0.15)
				)
				(justify left bottom mirror)
			)
		)
		(fp_text user "${REFERENCE}"
			(at -0.95 -3.168 0)
			(layer "B.Fab")
			(effects
				(font
					(size 0.7 0.7)
					(thickness 0.15)
				)
				(justify left bottom mirror)
			)
		)
		(pad "1" smd roundrect
			(at -0.48 0 180)
			(size 0.59 0.64)
			(layers "B.Cu" "B.Mask" "B.Paste")
			(roundrect_rratio 0.25)
			(net 1 "GND")
			(pintype "passive")
		)
		(pad "2" smd roundrect
			(at 0.48 0 180)
			(size 0.59 0.64)
			(layers "B.Cu" "B.Mask" "B.Paste")
			(roundrect_rratio 0.25)
			(net 169 "/SoM_IO2/SFI_REFCLK+")
			(pintype "passive")
		)
	)
)
